(kicad_pcb
	(version 20260206)
	(generator "pcbnew")
	(generator_version "10.0")
	(general
		(thickness 1.6)
		(legacy_teardrops no)
	)
	(paper "A4")
	(title_block
		(title "v1-tray-backplane — T6M_tray_BP_c_1023_1120.brd")
		(comment 1 "Open CloudServer (Microsoft) / footprints 150-155 of 170")
	)
	(layers
		(0 "F.Cu" signal "TOP")
		(4 "In1.Cu" signal "GND")
		(6 "In2.Cu" signal "IN1")
		(8 "In3.Cu" signal "VCC")
		(10 "In4.Cu" signal "VCC1")
		(12 "In5.Cu" signal "IN2")
		(14 "In6.Cu" signal "GND1")
		(2 "B.Cu" signal "BOTTOM")
		(9 "F.Adhes" user "F.Adhesive")
		(11 "B.Adhes" user "B.Adhesive")
		(13 "F.Paste" user "Package Geometry/Pastemask Top")
		(15 "B.Paste" user "Package Geometry/Pastemask Bottom")
		(5 "F.SilkS" user "Ref Des/Silkscreen Top")
		(7 "B.SilkS" user "Ref Des/Silkscreen Bottom")
		(1 "F.Mask" user "Board Geometry/Soldermask Top")
		(3 "B.Mask" user "Board Geometry/Soldermask Bottom")
		(17 "Dwgs.User" user "User.Drawings")
		(19 "Cmts.User" user "User.Comments")
		(21 "Eco1.User" user "User.Eco1")
		(23 "Eco2.User" user "User.Eco2")
		(25 "Edge.Cuts" user "Board Geometry/Outline")
		(27 "Margin" user)
		(31 "F.CrtYd" user "Package Geometry/Place Bound Top")
		(29 "B.CrtYd" user "Package Geometry/Place Bound Bottom")
		(35 "F.Fab" user "Ref Des/Assembly Top")
		(33 "B.Fab" user "Ref Des/Assembly Bottom")
	)
	(footprint ""
		(layer "F.Cu")
		(at 89.41816 -29.122878 180)
		(property "Reference" "R47"
			(at 7.13232 -1.080008 0)
			(unlocked yes)
			(layer "F.SilkS")
			(effects
				(font
					(size 0.7874 0.5842)
					(thickness 0.1524)
				)
				(justify left)
			)
		)
		(property "Value" ""
			(at 0 0 180)
			(layer "F.Fab")
			(effects
				(font
					(size 1.27 1.27)
				)
			)
		)
		(duplicate_pad_numbers_are_jumpers no)
		(fp_line
			(start 0.7874 0.4064)
			(end -0.7874 0.4064)
			(stroke
				(width 0.1524)
				(type default)
			)
			(layer "F.SilkS")
		)
		(fp_line
			(start 0.7874 -0.4064)
			(end 0.7874 0.4064)
			(stroke
				(width 0.1524)
				(type default)
			)
			(layer "F.SilkS")
		)
		(fp_line
			(start -0.7874 0.4064)
			(end -0.7874 -0.4064)
			(stroke
				(width 0.1524)
				(type default)
			)
			(layer "F.SilkS")
		)
		(fp_line
			(start -0.7874 -0.4064)
			(end 0.7874 -0.4064)
			(stroke
				(width 0.1524)
				(type default)
			)
			(layer "F.SilkS")
		)
		(fp_poly
			(pts
				(xy -0.508 0.2794) (xy -0.508 0.2286) (xy -0.635 0.2286) (xy -0.635 -0.254) (xy -0.5334 -0.254)
				(xy -0.5334 -0.2794) (xy 0.5334 -0.2794) (xy 0.5334 -0.254) (xy 0.635 -0.254) (xy 0.635 0.254) (xy 0.5334 0.254)
				(xy 0.5334 0.2794)
			)
			(stroke
				(width 0)
				(type default)
			)
			(fill no)
			(layer "F.CrtYd")
		)
		(pad "1" smd rect
			(at 0.40005 0 180)
			(size 0.4572 0.508)
			(layers "F.Cu" "F.Mask" "F.Paste")
			(net "GND")
		)
		(pad "2" smd rect
			(at -0.40005 0 180)
			(size 0.4572 0.508)
			(layers "F.Cu" "F.Mask" "F.Paste")
			(net "ENET10G_2_TX_DIS")
		)
	)
	(footprint ""
		(layer "F.Cu")
		(at 121.31802 -21.552662 90)
		(property "Reference" "R34"
			(at -6.2738 -59.604148 90)
			(unlocked yes)
			(layer "F.SilkS")
			(effects
				(font
					(size 0.7874 0.5842)
					(thickness 0.1524)
				)
				(justify left)
			)
		)
		(property "Value" ""
			(at 0 0 90)
			(layer "F.Fab")
			(effects
				(font
					(size 1.27 1.27)
				)
			)
		)
		(duplicate_pad_numbers_are_jumpers no)
		(fp_line
			(start 0.7874 -0.4064)
			(end 0.7874 0.4064)
			(stroke
				(width 0.1524)
				(type default)
			)
			(layer "F.SilkS")
		)
		(fp_line
			(start -0.7874 -0.4064)
			(end 0.7874 -0.4064)
			(stroke
				(width 0.1524)
				(type default)
			)
			(layer "F.SilkS")
		)
		(fp_line
			(start 0.7874 0.4064)
			(end -0.7874 0.4064)
			(stroke
				(width 0.1524)
				(type default)
			)
			(layer "F.SilkS")
		)
		(fp_line
			(start -0.7874 0.4064)
			(end -0.7874 -0.4064)
			(stroke
				(width 0.1524)
				(type default)
			)
			(layer "F.SilkS")
		)
		(fp_poly
			(pts
				(xy -0.508 0.2794) (xy -0.508 0.2286) (xy -0.635 0.2286) (xy -0.635 -0.254) (xy -0.5334 -0.254)
				(xy -0.5334 -0.2794) (xy 0.5334 -0.2794) (xy 0.5334 -0.254) (xy 0.635 -0.254) (xy 0.635 0.254) (xy 0.5334 0.254)
				(xy 0.5334 0.2794)
			)
			(stroke
				(width 0)
				(type default)
			)
			(fill no)
			(layer "F.CrtYd")
		)
		(pad "1" smd rect
			(at 0.40005 0 90)
			(size 0.4572 0.508)
			(layers "F.Cu" "F.Mask" "F.Paste")
			(net "GND")
		)
		(pad "2" smd rect
			(at -0.40005 0 90)
			(size 0.4572 0.508)
			(layers "F.Cu" "F.Mask" "F.Paste")
			(net "BLADE1_MATED_N")
		)
	)
	(footprint ""
		(layer "F.Cu")
		(at 313.07024 -28.966922)
		(property "Reference" "R20"
			(at -6.5786 -0.955548 0)
			(unlocked yes)
			(layer "F.SilkS")
			(effects
				(font
					(size 0.7874 0.5842)
					(thickness 0.1524)
				)
				(justify left)
			)
		)
		(property "Value" ""
			(at 0 0 0)
			(layer "F.Fab")
			(effects
				(font
					(size 1.27 1.27)
				)
			)
		)
		(duplicate_pad_numbers_are_jumpers no)
		(fp_line
			(start -0.7874 -0.4064)
			(end 0.7874 -0.4064)
			(stroke
				(width 0.1524)
				(type default)
			)
			(layer "F.SilkS")
		)
		(fp_line
			(start -0.7874 0.4064)
			(end -0.7874 -0.4064)
			(stroke
				(width 0.1524)
				(type default)
			)
			(layer "F.SilkS")
		)
		(fp_line
			(start 0.7874 -0.4064)
			(end 0.7874 0.4064)
			(stroke
				(width 0.1524)
				(type default)
			)
			(layer "F.SilkS")
		)
		(fp_line
			(start 0.7874 0.4064)
			(end -0.7874 0.4064)
			(stroke
				(width 0.1524)
				(type default)
			)
			(layer "F.SilkS")
		)
		(fp_poly
			(pts
				(xy -0.508 0.2794) (xy -0.508 0.2286) (xy -0.635 0.2286) (xy -0.635 -0.254) (xy -0.5334 -0.254)
				(xy -0.5334 -0.2794) (xy 0.5334 -0.2794) (xy 0.5334 -0.254) (xy 0.635 -0.254) (xy 0.635 0.254) (xy 0.5334 0.254)
				(xy 0.5334 0.2794)
			)
			(stroke
				(width 0)
				(type default)
			)
			(fill no)
			(layer "F.CrtYd")
		)
		(pad "1" smd rect
			(at 0.40005 0)
			(size 0.4572 0.508)
			(layers "F.Cu" "F.Mask" "F.Paste")
			(net "P3V3_BLAD2")
		)
		(pad "2" smd rect
			(at -0.40005 0)
			(size 0.4572 0.508)
			(layers "F.Cu" "F.Mask" "F.Paste")
			(net "ENET10G_4_TX_DIS")
		)
	)
	(footprint ""
		(layer "F.Cu")
		(at 425.809918 -29.100018)
		(property "Reference" "GNDPAD1"
			(at 0.659384 9.954768 90)
			(unlocked yes)
			(layer "F.SilkS")
			(effects
				(font
					(size 0.7874 0.5842)
					(thickness 0.1524)
				)
				(justify left)
			)
		)
		(property "Value" ""
			(at 0 0 0)
			(layer "F.Fab")
			(effects
				(font
					(size 1.27 1.27)
				)
			)
		)
		(duplicate_pad_numbers_are_jumpers no)
		(fp_poly
			(pts
				(xy -1.3589 2.4511) (xy 1.3589 2.4511) (xy 1.3589 -2.4511) (xy -1.3589 -2.4511)
			)
			(stroke
				(width 0)
				(type default)
			)
			(fill no)
			(layer "F.CrtYd")
		)
		(pad "1" smd rect
			(at 0 0)
			(size 2.6162 4.8006)
			(layers "F.Cu" "F.Mask" "F.Paste")
			(net "GND")
		)
	)
	(footprint ""
		(layer "F.Cu")
		(at 375.82856 -23.636478 180)
		(property "Reference" "R17"
			(at -33.86328 -16.650208 0)
			(unlocked yes)
			(layer "F.SilkS")
			(effects
				(font
					(size 0.7874 0.5842)
					(thickness 0.1524)
				)
				(justify left)
			)
		)
		(property "Value" ""
			(at 0 0 180)
			(layer "F.Fab")
			(effects
				(font
					(size 1.27 1.27)
				)
			)
		)
		(duplicate_pad_numbers_are_jumpers no)
		(fp_line
			(start 0.7874 0.4064)
			(end -0.7874 0.4064)
			(stroke
				(width 0.1524)
				(type default)
			)
			(layer "F.SilkS")
		)
		(fp_line
			(start 0.7874 -0.4064)
			(end 0.7874 0.4064)
			(stroke
				(width 0.1524)
				(type default)
			)
			(layer "F.SilkS")
		)
		(fp_line
			(start -0.7874 0.4064)
			(end -0.7874 -0.4064)
			(stroke
				(width 0.1524)
				(type default)
			)
			(layer "F.SilkS")
		)
		(fp_line
			(start -0.7874 -0.4064)
			(end 0.7874 -0.4064)
			(stroke
				(width 0.1524)
				(type default)
			)
			(layer "F.SilkS")
		)
		(fp_poly
			(pts
				(xy -0.508 0.2794) (xy -0.508 0.2286) (xy -0.635 0.2286) (xy -0.635 -0.254) (xy -0.5334 -0.254)
				(xy -0.5334 -0.2794) (xy 0.5334 -0.2794) (xy 0.5334 -0.254) (xy 0.635 -0.254) (xy 0.635 0.254) (xy 0.5334 0.254)
				(xy 0.5334 0.2794)
			)
			(stroke
				(width 0)
				(type default)
			)
			(fill no)
			(layer "F.CrtYd")
		)
		(pad "1" smd rect
			(at 0.40005 0 180)
			(size 0.4572 0.508)
			(layers "F.Cu" "F.Mask" "F.Paste")
			(net "P3V3_BLAD2")
		)
		(pad "2" smd rect
			(at -0.40005 0 180)
			(size 0.4572 0.508)
			(layers "F.Cu" "F.Mask" "F.Paste")
			(net "ENET10G_3_TX_FAULT")
		)
	)
	(footprint ""
		(layer "F.Cu")
		(at 142.9512 -3.048 90)
		(property "Reference" "C21"
			(at -2.1844 -8.092948 90)
			(unlocked yes)
			(layer "F.SilkS")
			(effects
				(font
					(size 0.7874 0.5842)
					(thickness 0.1524)
				)
				(justify left)
			)
		)
		(property "Value" ""
			(at 0 0 90)
			(layer "F.Fab")
			(effects
				(font
					(size 1.27 1.27)
				)
			)
		)
		(duplicate_pad_numbers_are_jumpers no)
		(fp_line
			(start 0.7874 -0.4064)
			(end 0.7874 0.4064)
			(stroke
				(width 0.1524)
				(type default)
			)
			(layer "F.SilkS")
		)
		(fp_line
			(start -0.7874 -0.4064)
			(end 0.7874 -0.4064)
			(stroke
				(width 0.1524)
				(type default)
			)
			(layer "F.SilkS")
		)
		(fp_line
			(start 0 0.381)
			(end 0 -0.381)
			(stroke
				(width 0.1524)
				(type default)
			)
			(layer "F.SilkS")
		)
		(fp_line
			(start 0.7874 0.4064)
			(end -0.7874 0.4064)
			(stroke
				(width 0.1524)
				(type default)
			)
			(layer "F.SilkS")
		)
		(fp_line
			(start -0.7874 0.4064)
			(end -0.7874 -0.4064)
			(stroke
				(width 0.1524)
				(type default)
			)
			(layer "F.SilkS")
		)
		(fp_poly
			(pts
				(xy -0.5334 0.254) (xy -0.635 0.254) (xy -0.635 0.2286) (xy -0.635 -0.254) (xy -0.5334 -0.254) (xy -0.5334 -0.2794)
				(xy 0.5334 -0.2794) (xy 0.5334 -0.254) (xy 0.635 -0.254) (xy 0.635 0.254) (xy 0.5334 0.254) (xy 0.5334 0.2794)
				(xy -0.508 0.2794) (xy -0.5334 0.2794)
			)
			(stroke
				(width 0)
				(type default)
			)
			(fill no)
			(layer "F.CrtYd")
		)
		(pad "1" smd rect
			(at 0.40005 0 90)
			(size 0.4572 0.508)
			(layers "F.Cu" "F.Mask" "F.Paste")
			(net "P3V3_10G_1_VCCR")
		)
		(pad "2" smd rect
			(at -0.40005 0 90)
			(size 0.4572 0.508)
			(layers "F.Cu" "F.Mask" "F.Paste")
			(net "GND")
		)
	)
)
